FILE_TYPE = CONNECTIVITY;
{Allegro Design Entry HDL 17.4-2019 S026 (4007227) 1/17/2022}
"PAGE_NUMBER" = 171;
0"NC";
1"GND\g";
2"GND\g";
3"GND\g";
4"GND\g";
5"GND\g";
6"GND\g";
7"GND\g";
8"GND\g";
9"GND\g";
10"GND\g";
11"GND\g";
12"SW_P12V_AUX_PVDDCR_CPU0_P0_FLT\g";
13"SW_PVDDCR_CPU0_P0_SW5";
14"SW_PVDDCR_CPU0_P0_PH5";
15"SW_PVDDCR_CPU0_P0_BOOT5";
16"GND\g";
17"SW_P12V_AUX_PVDDCR_CPU0_P0_FLT\g";
18"PVDDCR_CPU0_P0_VCCS";
19"SW_PVDDCR_CPU0_P0_BOOT5_RC";
20"SW_PVDDCR_CPU0_P0_BOOT6";
21"SW_PVDDCR_CPU0_P0_BOOT6_RC";
22"SW_PVDDCR_CPU0_P0_PH6";
23"IND_CPU0_P0_CPL0";
24"SW_PVDDCR_CPU0_P0_SW6";
25"SW_PVDDCR_CPU0_P0_SW6_RC";
26"GND\g";
27"PVDDCR_CPU0_P0\g";
28"GND\g";
29"PVDDCR_CPU0_P0\g";
30"GND\g";
31"PVDDCR_CPU0_P0_PVCC\g";
32"GND\g";
33"GND\g";
34"PVDDCR_CPU0_P0_PVCC\g";
35"PVDDCR_CPU0_P0_VOS6";
36"PVDDCR_CPU0_P0_VOS5";
37"PVDDCR_CPU0_P0_VCCS";
38"PVDDCR_CPU0_P0_IMON6";
39"PVDDCR_CPU0_P0_LSET6";
40"NC_PVDDCR_CPU0_P0_GL2_6";
41"NC_PVDDCR_CPU0_P0_GL1_6";
42"PVDDCR_CPU0_P0_LSET5";
43"NC_PVDDCR_CPU0_P0_DNC5";
44"NC_PVDDCR_CPU0_P0_GL1_5";
45"IND_CPU0_P0_CPL6";
46"IND_CPU0_P0_CPL6";
47"IND_CPU0_P0_CPL5";
48"PVDDCR_CPU0_P0_VCC5";
49"PVDDCR_CPU0_P0_IMON5";
50"NC_PVDDCR_CPU0_P0_DNC6";
51"PVDDCR_CPU0_P0_PWM6";
52"PVDDCR_CPU0_P0_TEMP0";
53"SW_PVDDCR_CPU0_P0_SW5_RC";
54"PVDDCR_CPU0_P0_TEMP0";
55"PVDDCR_CPU0_P0_VCC6";
56"PVDDCR_CPU0_P0_PWM5";
57"NC_PVDDCR_CPU0_P0_GL2_5";
%"UNIVERSAL_GND"
"1","(-7200,2000)","0","pure_quanta_power","I10";
;
CDS_LIB"pure_quanta_power"
HDL_POWER"GND";
"A"1;
%"Q_CAP"
"1","(-7200,2200)","0","pure_quanta","I11";
;
LOCATION"PC151"
$SEC"1"
CDS_SEC"1"
PACK_TYPE"C0402"
VOLTAGE"10V"
VALUE"2.2UF"
TOLERANCE"10%"
MATERIAL"X6S"
CDS_LIB"pure_quanta"
PART_NUMBER"CH5222KEB01";
"B"
$PN"2"1;
"A"
$PN"1"55;
%"UNIVERSAL_GND"
"1","(-6850,2450)","0","pure_quanta_power","I12";
;
CDS_LIB"pure_quanta_power"
HDL_POWER"GND";
"A"2;
%"Q_RES"
"2","(-7200,2700)","0","pure_quanta","I13";
;
LOCATION"PR430"
$SEC"1"
CDS_SEC"1"
WATTAGE"1/16W"
MATERIAL"CHIP"
TOLERANCE"1%"
VALUE"2.2"
PACK_TYPE"0402LF"
CDS_LIB"pure_quanta"
PART_NUMBER"CS-2202FB01";
"A"
$PN"1"34;
"B"
$PN"2"55;
%"Q_CAP"
"1","(-6850,2725)","0","pure_quanta","I14";
;
LOCATION"PC152_C0P0_6"
$SEC"1"
CDS_SEC"1"
PACK_TYPE"C0402"
MATERIAL"X6S"
TOLERANCE"10%"
VOLTAGE"10V"
VALUE"2.2UF"
CDS_LIB"pure_quanta"
PART_NUMBER"CH5222KEB01";
"B"
$PN"2"2;
"A"
$PN"1"34;
%"UNIVERSAL_GND"
"1","(-7525,4025)","0","pure_quanta_power","I15";
;
CDS_LIB"pure_quanta_power"
HDL_POWER"GND";
"A"3;
%"VCC_CORE"
"1","(-7200,3125)","0","pure_quanta_power","I16";
;
HDL_POWER"PVDDCR_CPU0_P0_PVCC"
CDS_LIB"pure_quanta_power";
"A"34;
%"ISL99390FRZTR5935"
"1","(-5700,4575)","0","pure_quanta","I18";
;
LOCATION"PU48"
$SEC"1"
CDS_SEC"1"
MATERIAL"IC"
PART_TYPE"SMLF"
VALUE"ISL99390FRZ-TR5935"
CDS_LMAN_SYM_OUTLINE"-300,700,250,-650"
NEEDS_NO_SIZE"TRUE"
CDS_LIB"pure_quanta"
PART_NUMBER"AL099390004";
"PGND2"
$PN"7_9-20_24"32;
"GL2"
$PN"41"57;
"GL1"
$PN"6"44;
"DNC"
$PN"31"43;
"EN"
$PN"35"48;
"PGND3"
$PN"40"32;
"VOS"
$PN"1"36;
"VIN2"
$PN"30"17;
"PGND1"
$PN"5"32;
"SW"
$PN"10_19"13;
"LSET"
$PN"37"42;
"IOUT"
$PN"38"49;
"TOUT_FLT"
$PN"36"54;
"PVCC"
$PN"4"31;
"PHASE"
$PN"32"14;
"VIN1"
$PN"25_29"17;
"BOOT"
$PN"33"15;
"AGND"
$PN"2"32;
"VCC"
$PN"3"48;
"REFIN"
$PN"39"18;
"PWM"
$PN"34"56;
%"UNIVERSAL_GND"
"1","(-5150,1125)","0","pure_quanta_power","I19";
;
CDS_LIB"pure_quanta_power"
HDL_POWER"GND";
"A"33;
%"UNIVERSAL_GND"
"1","(-4225,950)","0","pure_quanta_power","I20";
;
CDS_LIB"pure_quanta_power"
HDL_POWER"GND";
"A"4;
%"Q_RES"
"1","(-3900,800)","0","pure_quanta","I21";
;
LOCATION"PR433"
$SEC"1"
CDS_SEC"1"
WATTAGE"1/16W"
MATERIAL"CHIP"
TOLERANCE"5%"
VALUE"0"
PACK_TYPE"0402LF"
CDS_LIB"pure_quanta"
PART_NUMBER"CS00002JB13";
"B"
$PN"2"29;
"A"
$PN"1"35;
%"Q_RES"
"2","(-4225,1175)","0","pure_quanta","I22";
;
LOCATION"PR500"
$SEC"1"
CDS_SEC"1"
MATERIAL"EMPTY"
WATTAGE"1/8W"
PACK_TYPE"0402LF"
VALUE"1.5"
TOLERANCE"1%"
CDS_LIB"pure_quanta"
PART_NUMBER"CS-1504FB00";
"A"
$PN"1"25;
"B"
$PN"2"4;
%"Q_CAP"
"1","(-4225,1675)","0","pure_quanta","I23";
;
LOCATION"PC182"
$SEC"1"
CDS_SEC"1"
PACK_TYPE"C0402"
TOLERANCE"10%"
VOLTAGE"50V"
VALUE"560PF"
MATERIAL"EMPTY"
CDS_LIB"pure_quanta"
PART_NUMBER"CH1566K1B09";
"B"
$PN"2"25;
"A"
$PN"1"24;
%"Q_CAP"
"1","(-4950,2725)","0","pure_quanta","I24";
;
LOCATION"PC153_6"
$SEC"1"
CDS_SEC"1"
PACK_TYPE"0402"
VOLTAGE"25V"
TOLERANCE"10%"
MATERIAL"X7R"
VALUE"0.1UF"
CDS_LIB"pure_quanta"
PART_NUMBER"CH4104K1B00";
"B"
$PN"2"11;
"A"
$PN"1"12;
%"UNIVERSAL_GND"
"1","(-5150,3850)","0","pure_quanta_power","I25";
;
CDS_LIB"pure_quanta_power"
HDL_POWER"GND";
"A"32;
%"Q_RES"
"1","(-4275,2200)","0","pure_quanta","I26";
;
LOCATION"PR432"
$SEC"1"
CDS_SEC"1"
TOLERANCE"1%"
PACK_TYPE"0402LF"
WATTAGE"1/16W"
MATERIAL"CHIP"
VALUE"5.6"
CDS_LIB"pure_quanta"
PART_NUMBER"CS-5602FB01";
"B"
$PN"2"21;
"A"
$PN"1"20;
%"Q_CAP"
"1","(-4575,2725)","0","pure_quanta","I27";
;
LOCATION"PC154_6"
$SEC"1"
CDS_SEC"1"
VOLTAGE"25V"
TOLERANCE"10%"
MATERIAL"X6S"
VALUE"1UF"
PACK_TYPE"C0402"
CDS_LIB"pure_quanta"
PART_NUMBER"CH5104KEB02";
"B"
$PN"2"11;
"A"
$PN"1"12;
%"Q_CAP"
"1","(-4250,2725)","0","pure_quanta","I28";
;
LOCATION"PC157_6"
$SEC"1"
CDS_SEC"1"
VALUE"22UF"
PACK_TYPE"C0805"
MATERIAL"X6S"
TOLERANCE"20%"
VOLTAGE"16V"
CDS_LIB"pure_quanta"
PART_NUMBER"CH6223MEA01";
"B"
$PN"2"11;
"A"
$PN"1"12;
%"Q_CAP"
"1","(-3925,2725)","0","pure_quanta","I29";
;
LOCATION"PC158_6"
$SEC"1"
CDS_SEC"1"
PACK_TYPE"C0805"
VALUE"22UF"
TOLERANCE"20%"
VOLTAGE"16V"
MATERIAL"X6S"
CDS_LIB"pure_quanta"
PART_NUMBER"CH6223MEA01";
"B"
$PN"2"11;
"A"
$PN"1"12;
%"UNIVERSAL_GND"
"1","(-7525,1300)","0","pure_quanta_power","I3";
;
CDS_LIB"pure_quanta_power"
HDL_POWER"GND";
"A"5;
%"UNIVERSAL_GND"
"1","(-4200,3725)","0","pure_quanta_power","I30";
;
CDS_LIB"pure_quanta_power"
HDL_POWER"GND";
"A"6;
%"Q_RES"
"2","(-4200,3950)","0","pure_quanta","I31";
;
LOCATION"PR501"
$SEC"1"
CDS_SEC"1"
TOLERANCE"1%"
PACK_TYPE"0402LF"
MATERIAL"EMPTY"
WATTAGE"1/8W"
VALUE"1.5"
CDS_LIB"pure_quanta"
PART_NUMBER"CS-1504FB00";
"A"
$PN"1"53;
"B"
$PN"2"6;
%"Q_RES"
"1","(-3625,3625)","0","pure_quanta","I32";
;
LOCATION"PR355"
$SEC"1"
CDS_SEC"1"
WATTAGE"1/16W"
MATERIAL"CHIP"
TOLERANCE"5%"
VALUE"0"
PACK_TYPE"0402LF"
CDS_LIB"pure_quanta"
PART_NUMBER"CS00002JB13";
"B"
$PN"2"27;
"A"
$PN"1"36;
%"Q_CAP"
"1","(-7525,4300)","0","pure_quanta","I33";
;
LOCATION"PC566_5"
$SEC"1"
CDS_SEC"1"
PACK_TYPE"0402"
VOLTAGE"25V"
VALUE"0.1UF"
TOLERANCE"10%"
MATERIAL"X7R"
CDS_LIB"pure_quanta"
PART_NUMBER"CH4104K1B00";
"B"
$PN"2"3;
"A"
$PN"1"18;
%"UNIVERSAL_GND"
"1","(-7200,4100)","0","pure_quanta_power","I34";
;
CDS_LIB"pure_quanta_power"
HDL_POWER"GND";
"A"7;
%"Q_RES"
"1","(-6875,4275)","0","pure_quanta","I36";
;
LOCATION"PR353"
$SEC"1"
CDS_SEC"1"
WATTAGE"1/16W"
MATERIAL"EMPTY"
TOLERANCE"1%"
VALUE"8.87K"
PACK_TYPE"0402LF"
CDS_LIB"pure_quanta"
PART_NUMBER"CS28872FB01";
"B"
$PN"2"42;
"A"
$PN"1"7;
%"UNIVERSAL_GND"
"1","(-7200,4725)","0","pure_quanta_power","I37";
;
CDS_LIB"pure_quanta_power"
HDL_POWER"GND";
"A"8;
%"Q_CAP"
"1","(-7200,4925)","0","pure_quanta","I38";
;
LOCATION"PC567"
$SEC"1"
CDS_SEC"1"
PACK_TYPE"C0402"
VOLTAGE"10V"
VALUE"2.2UF"
TOLERANCE"10%"
MATERIAL"X6S"
CDS_LIB"pure_quanta"
PART_NUMBER"CH5222KEB01";
"B"
$PN"2"8;
"A"
$PN"1"48;
%"Q_CAP"
"1","(-7525,1575)","0","pure_quanta","I4";
;
LOCATION"PC150_6"
$SEC"1"
CDS_SEC"1"
PACK_TYPE"0402"
VOLTAGE"25V"
VALUE"0.1UF"
TOLERANCE"10%"
MATERIAL"X7R"
CDS_LIB"pure_quanta"
PART_NUMBER"CH4104K1B00";
"B"
$PN"2"5;
"A"
$PN"1"37;
%"Q_RES"
"2","(-7200,5425)","0","pure_quanta","I40";
;
LOCATION"PR352"
$SEC"1"
CDS_SEC"1"
MATERIAL"CHIP"
TOLERANCE"1%"
VALUE"2.2"
WATTAGE"1/16W"
PACK_TYPE"0402LF"
CDS_LIB"pure_quanta"
PART_NUMBER"CS-2202FB01";
"A"
$PN"1"31;
"B"
$PN"2"48;
%"UNIVERSAL_GND"
"1","(-6850,5175)","0","pure_quanta_power","I41";
;
CDS_LIB"pure_quanta_power"
HDL_POWER"GND";
"A"9;
%"Q_CAP"
"1","(-6850,5425)","0","pure_quanta","I42";
;
LOCATION"PC568_C0P0_5"
$SEC"1"
CDS_SEC"1"
PACK_TYPE"C0402"
VOLTAGE"10V"
VALUE"2.2UF"
TOLERANCE"10%"
MATERIAL"X6S"
CDS_LIB"pure_quanta"
PART_NUMBER"CH5222KEB01";
"B"
$PN"2"9;
"A"
$PN"1"31;
%"VCC_CORE"
"1","(-7200,5825)","0","pure_quanta_power","I43";
;
HDL_POWER"PVDDCR_CPU0_P0_PVCC"
CDS_LIB"pure_quanta_power";
"A"31;
%"Q_CAP"
"1","(-4950,5450)","0","pure_quanta","I44";
;
LOCATION"PC570_5"
$SEC"1"
CDS_SEC"1"
PACK_TYPE"0402"
TOLERANCE"10%"
VOLTAGE"25V"
MATERIAL"X7R"
VALUE"0.1UF"
CDS_LIB"pure_quanta"
PART_NUMBER"CH4104K1B00";
"B"
$PN"2"16;
"A"
$PN"1"17;
%"Q_RES"
"1","(-4275,4925)","0","pure_quanta","I45";
;
LOCATION"PR354"
$SEC"1"
CDS_SEC"1"
WATTAGE"1/16W"
TOLERANCE"1%"
PACK_TYPE"0402LF"
VALUE"5.6"
MATERIAL"CHIP"
CDS_LIB"pure_quanta"
PART_NUMBER"CS-5602FB01";
"B"
$PN"2"19;
"A"
$PN"1"15;
%"Q_CAP"
"1","(-4200,4400)","0","pure_quanta","I46";
;
LOCATION"PC184"
$SEC"1"
CDS_SEC"1"
VALUE"560PF"
TOLERANCE"10%"
MATERIAL"EMPTY"
VOLTAGE"50V"
PACK_TYPE"C0402"
CDS_LIB"pure_quanta"
PART_NUMBER"CH1566K1B09";
"B"
$PN"2"53;
"A"
$PN"1"13;
%"Q_CAP"
"1","(-4575,5450)","0","pure_quanta","I47";
;
LOCATION"PC569_5"
$SEC"1"
CDS_SEC"1"
MATERIAL"X6S"
VOLTAGE"25V"
VALUE"1UF"
PACK_TYPE"C0402"
TOLERANCE"10%"
CDS_LIB"pure_quanta"
PART_NUMBER"CH5104KEB02";
"B"
$PN"2"16;
"A"
$PN"1"17;
%"Q_CAP"
"1","(-4250,5450)","0","pure_quanta","I48";
;
LOCATION"PC571_5"
$SEC"1"
CDS_SEC"1"
PACK_TYPE"C0805"
VALUE"22UF"
VOLTAGE"16V"
TOLERANCE"20%"
MATERIAL"X6S"
CDS_LIB"pure_quanta"
PART_NUMBER"CH6223MEA01";
"B"
$PN"2"16;
"A"
$PN"1"17;
%"Q_CAP"
"1","(-3900,5450)","0","pure_quanta","I49";
;
LOCATION"PC572_5"
$SEC"1"
CDS_SEC"1"
VALUE"22UF"
MATERIAL"X6S"
VOLTAGE"16V"
TOLERANCE"20%"
PACK_TYPE"C0805"
CDS_LIB"pure_quanta"
PART_NUMBER"CH6223MEA01";
"B"
$PN"2"16;
"A"
$PN"1"17;
%"UNIVERSAL_GND"
"1","(-7200,1375)","0","pure_quanta_power","I5";
;
CDS_LIB"pure_quanta_power"
HDL_POWER"GND";
"A"10;
%"UNIVERSAL_GND"
"1","(-3625,1500)","0","pure_quanta_power","I50";
;
CDS_LIB"pure_quanta_power"
HDL_POWER"GND";
"A"26;
%"Q_INDUCTOR"
"1","(-3450,1625)","0","pure_quanta","I51";
;
LOCATION"PL50"
$SEC"1"
CDS_SEC"1"
PACK_TYPE"SMLF"
VALUE"120NH/69A"
MATERIAL"IND"
CDS_LIB"pure_quanta"
NEEDS_NO_SIZE"TRUE"
PART_NUMBER"CV+12^0EZ03";
"1"
$PN"1"26;
"2"
$PN"2"23;
%"Q_INDUCTOR4P_14"
"1","(-2475,1725)","0","pure_quanta","I52";
;
LOCATION"PL70"
$SEC"1"
CDS_SEC"1"
VALUE"150NH"
PART_TYPE"SMLF"
MATERIAL"IND"
CDS_LIB"pure_quanta"
NEEDS_NO_SIZE"TRUE"
PART_NUMBER"CV+15^0TZ04";
"1"
$PN"1"24;
"4"
$PN"4"29;
"3"
$PN"3"45;
"2"
$PN"2"23;
%"UNIVERSAL_GND"
"1","(-3625,2375)","0","pure_quanta_power","I53";
;
CDS_LIB"pure_quanta_power"
HDL_POWER"GND";
"A"11;
%"Q_CAP"
"1","(-3275,2075)","0","pure_quanta","I54";
;
LOCATION"PC161"
$SEC"1"
CDS_SEC"1"
VOLTAGE"16V"
VALUE"0.22UF"
TOLERANCE"10%"
MATERIAL"X7R"
PACK_TYPE"0402"
CDS_LIB"pure_quanta"
PART_NUMBER"CH4223K1B00";
"B"
$PN"2"22;
"A"
$PN"1"21;
%"Q_CAP"
"1","(-3625,2725)","0","pure_quanta","I55";
;
LOCATION"PC159_6"
$SEC"1"
CDS_SEC"1"
TOLERANCE"20%"
VALUE"22UF"
VOLTAGE"16V"
MATERIAL"X6S"
PACK_TYPE"C0805"
CDS_LIB"pure_quanta"
PART_NUMBER"CH6223MEA01";
"B"
$PN"2"11;
"A"
$PN"1"12;
%"VCC_CORE"
"1","(-3625,3025)","0","pure_quanta_power","I56";
;
HDL_POWER"SW_P12V_AUX_PVDDCR_CPU0_P0_FLT"
CDS_LIB"pure_quanta_power";
"A"12;
%"UNIVERSAL_GND"
"1","(-650,1325)","0","pure_quanta_power","I58";
;
CDS_LIB"pure_quanta_power"
HDL_POWER"GND";
"A"30;
%"Q_CAP"
"1","(-1075,1675)","0","pure_quanta","I59";
;
LOCATION"PC163_6"
$SEC"1"
CDS_SEC"1"
PACK_TYPE"C0805"
MATERIAL"X6S"
TOLERANCE"20%"
VALUE"22UF"
VOLTAGE"4V"
CDS_LIB"pure_quanta"
PART_NUMBER"CH622KMEA03";
"B"
$PN"2"30;
"A"
$PN"1"29;
%"Q_CAP"
"1","(-650,1675)","0","pure_quanta","I60";
;
LOCATION"PC166_6"
$SEC"1"
CDS_SEC"1"
PACK_TYPE"C0805"
MATERIAL"X6S"
TOLERANCE"20%"
VALUE"22UF"
VOLTAGE"4V"
CDS_LIB"pure_quanta"
PART_NUMBER"CH622KMEA03";
"B"
$PN"2"30;
"A"
$PN"1"29;
%"VCC_CORE"
"1","(-650,2000)","0","pure_quanta_power","I61";
;
HDL_POWER"PVDDCR_CPU0_P0"
CDS_LIB"pure_quanta_power";
"A"29;
%"Q_CAP"
"1","(-3275,4800)","0","pure_quanta","I63";
;
LOCATION"PC574"
$SEC"1"
CDS_SEC"1"
MATERIAL"X7R"
PACK_TYPE"0402"
VALUE"0.22UF"
VOLTAGE"16V"
TOLERANCE"10%"
CDS_LIB"pure_quanta"
PART_NUMBER"CH4223K1B00";
"B"
$PN"2"14;
"A"
$PN"1"19;
%"Q_INDUCTOR4P_14"
"1","(-2475,4450)","0","pure_quanta","I64";
;
LOCATION"PL61"
$SEC"1"
CDS_SEC"1"
PART_TYPE"SMLF"
VALUE"150NH"
MATERIAL"IND"
NEEDS_NO_SIZE"TRUE"
CDS_LIB"pure_quanta"
PART_NUMBER"CV+15^0TZ04";
"1"
$PN"1"13;
"4"
$PN"4"27;
"3"
$PN"3"47;
"2"
$PN"2"46;
%"UNIVERSAL_GND"
"1","(-3550,5100)","0","pure_quanta_power","I65";
;
CDS_LIB"pure_quanta_power"
HDL_POWER"GND";
"A"16;
%"Q_CAP"
"1","(-3550,5450)","0","pure_quanta","I66";
;
LOCATION"PC573_5"
$SEC"1"
CDS_SEC"1"
MATERIAL"X6S"
VOLTAGE"16V"
VALUE"22UF"
TOLERANCE"20%"
PACK_TYPE"C0805"
CDS_LIB"pure_quanta"
PART_NUMBER"CH6223MEA01";
"B"
$PN"2"16;
"A"
$PN"1"17;
%"VCC_CORE"
"1","(-3550,5750)","0","pure_quanta_power","I67";
;
HDL_POWER"SW_P12V_AUX_PVDDCR_CPU0_P0_FLT"
CDS_LIB"pure_quanta_power";
"A"17;
%"Q_CAP"
"1","(-1075,4400)","0","pure_quanta","I69";
;
LOCATION"PC575_5"
$SEC"1"
CDS_SEC"1"
PACK_TYPE"C0805"
MATERIAL"X6S"
TOLERANCE"20%"
VALUE"22UF"
VOLTAGE"4V"
CDS_LIB"pure_quanta"
PART_NUMBER"CH622KMEA03";
"B"
$PN"2"28;
"A"
$PN"1"27;
%"UNIVERSAL_GND"
"1","(-650,4050)","0","pure_quanta_power","I70";
;
CDS_LIB"pure_quanta_power"
HDL_POWER"GND";
"A"28;
%"Q_CAP"
"1","(-650,4400)","0","pure_quanta","I71";
;
LOCATION"PC576_5"
$SEC"1"
CDS_SEC"1"
PACK_TYPE"C0805"
MATERIAL"X6S"
TOLERANCE"20%"
VALUE"22UF"
VOLTAGE"4V"
CDS_LIB"pure_quanta"
PART_NUMBER"CH622KMEA03";
"B"
$PN"2"28;
"A"
$PN"1"27;
%"VCC_CORE"
"1","(-650,4725)","0","pure_quanta_power","I72";
;
HDL_POWER"PVDDCR_CPU0_P0"
CDS_LIB"pure_quanta_power";
"A"27;
%"ISL99390FRZTR5935"
"1","(-5700,1850)","0","pure_quanta","I73";
;
LOCATION"PU10"
$SEC"1"
CDS_SEC"1"
VALUE"ISL99390FRZ-TR5935"
MATERIAL"IC"
PART_TYPE"SMLF"
CDS_LMAN_SYM_OUTLINE"-300,700,250,-650"
NEEDS_NO_SIZE"TRUE"
CDS_LIB"pure_quanta"
PART_NUMBER"AL099390004";
"PGND2"
$PN"7_9-20_24"33;
"GL2"
$PN"41"40;
"GL1"
$PN"6"41;
"DNC"
$PN"31"50;
"EN"
$PN"35"55;
"PGND3"
$PN"40"33;
"VOS"
$PN"1"35;
"VIN2"
$PN"30"12;
"PGND1"
$PN"5"33;
"SW"
$PN"10_19"24;
"LSET"
$PN"37"39;
"IOUT"
$PN"38"38;
"TOUT_FLT"
$PN"36"52;
"PVCC"
$PN"4"34;
"PHASE"
$PN"32"22;
"VIN1"
$PN"25_29"12;
"BOOT"
$PN"33"20;
"AGND"
$PN"2"33;
"VCC"
$PN"3"55;
"REFIN"
$PN"39"37;
"PWM"
$PN"34"51;
%"Q_RES"
"1","(-6875,1550)","0","pure_quanta","I8";
;
LOCATION"PR431"
$SEC"1"
CDS_SEC"1"
PACK_TYPE"0402LF"
VALUE"8.87K"
TOLERANCE"1%"
MATERIAL"EMPTY"
WATTAGE"1/16W"
CDS_LIB"pure_quanta"
PART_NUMBER"CS28872FB01";
"B"
$PN"2"39;
"A"
$PN"1"10;
END.
